# S9S_MB_2U (Grand Teton) — schematic netlist excerpt (pin names and nets, part order shuffled) for the footprints in the layout excerpt that follows; sources: Cadence DE-HDL packaged netlist, KiCad conversion of 03242023_DA0F0TMBIJ0_F0T_Motherboard_J_brd_V01_OCP.brd

L1  Q_INDUCTOR  FCM2012KF-601T/0.5A IND  pkg SMLF  page 210 : \1\ = P3V3_AUX ; \2\ = P3V3_AUX_CLK_GEN_VDD_CK440
R3345  Q_RES  1 1% CHIP  pkg 0603LF  page 217 : A = P3V3_AUX ; B = P3V3_AUX_FPGA_VCCIO4

(kicad_pcb
	(version 20260206)
	(generator "pcbnew")
	(generator_version "10.0")
	(general
		(thickness 1.6)
		(legacy_teardrops no)
	)
	(paper "A4")
	(title_block
		(title "03242023_DA0F0TMBIJ0_F0T_Motherboard_J_brd_V01_OCP.brd")
		(comment 1 "Grand Teton / footprints 4313-4314 of 6105")
	)
	(layers
		(0 "F.Cu" signal "TOP")
		(4 "In1.Cu" signal "GND")
		(6 "In2.Cu" signal "IN1")
		(8 "In3.Cu" signal "GND1")
		(10 "In4.Cu" signal "IN2")
		(12 "In5.Cu" signal "GND2")
		(14 "In6.Cu" signal "IN3")
		(16 "In7.Cu" signal "GND3")
		(18 "In8.Cu" signal "VCC")
		(20 "In9.Cu" signal "VCC1")
		(22 "In10.Cu" signal "GND4")
		(24 "In11.Cu" signal "IN4")
		(26 "In12.Cu" signal "GND5")
		(28 "In13.Cu" signal "IN5")
		(30 "In14.Cu" signal "GND6")
		(32 "In15.Cu" signal "IN6")
		(34 "In16.Cu" signal "GND7")
		(2 "B.Cu" signal "BOTTOM")
		(9 "F.Adhes" user "F.Adhesive")
		(11 "B.Adhes" user "B.Adhesive")
		(13 "F.Paste" user "Package Geometry/Pastemask Top")
		(15 "B.Paste" user "Package Geometry/Pastemask Bottom")
		(5 "F.SilkS" user "Ref Des/Silkscreen Top")
		(7 "B.SilkS" user "Ref Des/Silkscreen Bottom")
		(1 "F.Mask" user "Board Geometry/Soldermask Top")
		(3 "B.Mask" user "Board Geometry/Soldermask Bottom")
		(17 "Dwgs.User" user "User.Drawings")
		(19 "Cmts.User" user "User.Comments")
		(21 "Eco1.User" user "User.Eco1")
		(23 "Eco2.User" user "User.Eco2")
		(25 "Edge.Cuts" user "Board Geometry/Outline")
		(27 "Margin" user)
		(31 "F.CrtYd" user "Package Geometry/Place Bound Top")
		(29 "B.CrtYd" user "Package Geometry/Place Bound Bottom")
		(35 "F.Fab" user "Ref Des/Assembly Top")
		(33 "B.Fab" user "Ref Des/Assembly Bottom")
	)
	(footprint ""
		(layer "B.Cu")
		(at 264.541 -98.008948 90)
		(property "Reference" "L1"
			(at 0 0 90)
			(layer "B.SilkS")
			(hide yes)
			(effects
				(font
					(size 1.27 1.27)
				)
				(justify mirror)
			)
		)
		(property "Value" ""
			(at 0 0 90)
			(layer "B.Fab")
			(effects
				(font
					(size 1.27 1.27)
				)
				(justify mirror)
			)
		)
		(duplicate_pad_numbers_are_jumpers no)
		(fp_line
			(start 1.63576 -0.8128)
			(end -1.63576 -0.8128)
			(stroke
				(width 0.1524)
				(type default)
			)
			(layer "B.SilkS")
		)
		(fp_line
			(start 1.63576 -0.8128)
			(end 1.63576 0.8128)
			(stroke
				(width 0.1524)
				(type default)
			)
			(layer "B.SilkS")
		)
		(fp_line
			(start -1.63576 -0.8128)
			(end -1.63576 0.8128)
			(stroke
				(width 0.1524)
				(type default)
			)
			(layer "B.SilkS")
		)
		(fp_line
			(start -1.63576 0.8128)
			(end 1.63576 0.8128)
			(stroke
				(width 0.1524)
				(type default)
			)
			(layer "B.SilkS")
		)
		(fp_line
			(start 1.56083 -0.738632)
			(end 1.56083 0.7366)
			(stroke
				(width 0.1)
				(type default)
			)
			(layer "B.Fab")
		)
		(fp_line
			(start -1.560576 -0.738632)
			(end 1.56083 -0.738632)
			(stroke
				(width 0.1)
				(type default)
			)
			(layer "B.Fab")
		)
		(fp_line
			(start 1.56083 0.7366)
			(end 1.524 0.7366)
			(stroke
				(width 0.1)
				(type default)
			)
			(layer "B.Fab")
		)
		(fp_line
			(start 1.524 0.7366)
			(end -1.524 0.7366)
			(stroke
				(width 0.1)
				(type default)
			)
			(layer "B.Fab")
		)
		(fp_line
			(start -1.524 0.7366)
			(end -1.560576 0.7366)
			(stroke
				(width 0.1)
				(type default)
			)
			(layer "B.Fab")
		)
		(fp_line
			(start -1.560576 0.7366)
			(end -1.560576 -0.738632)
			(stroke
				(width 0.1)
				(type default)
			)
			(layer "B.Fab")
		)
		(pad "1" smd rect
			(at 0.94996 0 90)
			(size 1.1176 1.3716)
			(layers "B.Cu" "B.Mask" "B.Paste")
			(net "P3V3_AUX")
		)
		(pad "2" smd rect
			(at -0.94996 0 90)
			(size 1.1176 1.3716)
			(layers "B.Cu" "B.Mask" "B.Paste")
			(net "P3V3_AUX_CLK_GEN_VDD_CK440")
		)
	)
	(footprint ""
		(layer "B.Cu")
		(at 178.10988 -101.564948 180)
		(property "Reference" "R3345"
			(at 0 0 0)
			(layer "B.SilkS")
			(hide yes)
			(effects
				(font
					(size 1.27 1.27)
				)
				(justify mirror)
			)
		)
		(property "Value" ""
			(at 0 0 0)
			(layer "B.Fab")
			(effects
				(font
					(size 1.27 1.27)
				)
				(justify mirror)
			)
		)
		(duplicate_pad_numbers_are_jumpers no)
		(fp_line
			(start 1.2954 0.5842)
			(end 1.2954 -0.5842)
			(stroke
				(width 0.1524)
				(type default)
			)
			(layer "B.SilkS")
		)
		(fp_line
			(start 1.2954 -0.5842)
			(end -1.2954 -0.5842)
			(stroke
				(width 0.1524)
				(type default)
			)
			(layer "B.SilkS")
		)
		(fp_line
			(start -1.2954 0.5842)
			(end 1.2954 0.5842)
			(stroke
				(width 0.1524)
				(type default)
			)
			(layer "B.SilkS")
		)
		(fp_line
			(start -1.2954 -0.5842)
			(end -1.2954 0.5842)
			(stroke
				(width 0.1524)
				(type default)
			)
			(layer "B.SilkS")
		)
		(fp_line
			(start 1.1938 0.4064)
			(end 1.1938 -0.406654)
			(stroke
				(width 0.1)
				(type default)
			)
			(layer "B.Fab")
		)
		(fp_line
			(start 1.1938 -0.406654)
			(end 0.8636 -0.406654)
			(stroke
				(width 0.1)
				(type default)
			)
			(layer "B.Fab")
		)
		(fp_line
			(start 0.8636 0.4572)
			(end 0.8636 0.4318)
			(stroke
				(width 0.1)
				(type default)
			)
			(layer "B.Fab")
		)
		(fp_line
			(start 0.8636 0.4318)
			(end 0.8636 0.4064)
			(stroke
				(width 0.1)
				(type default)
			)
			(layer "B.Fab")
		)
		(fp_line
			(start 0.8636 0.4064)
			(end 1.1938 0.4064)
			(stroke
				(width 0.1)
				(type default)
			)
			(layer "B.Fab")
		)
		(fp_line
			(start 0.8636 -0.406654)
			(end 0.8636 -0.4572)
			(stroke
				(width 0.1)
				(type default)
			)
			(layer "B.Fab")
		)
		(fp_line
			(start 0.8636 -0.4572)
			(end -0.8636 -0.4572)
			(stroke
				(width 0.1)
				(type default)
			)
			(layer "B.Fab")
		)
		(fp_line
			(start -0.8636 0.4572)
			(end 0.8636 0.4572)
			(stroke
				(width 0.1)
				(type default)
			)
			(layer "B.Fab")
		)
		(fp_line
			(start -0.8636 0.4064)
			(end -0.8636 0.4572)
			(stroke
				(width 0.1)
				(type default)
			)
			(layer "B.Fab")
		)
		(fp_line
			(start -0.8636 -0.406654)
			(end -1.1938 -0.406654)
			(stroke
				(width 0.1)
				(type default)
			)
			(layer "B.Fab")
		)
		(fp_line
			(start -0.8636 -0.4572)
			(end -0.8636 -0.406654)
			(stroke
				(width 0.1)
				(type default)
			)
			(layer "B.Fab")
		)
		(fp_line
			(start -1.1938 0.4064)
			(end -0.8636 0.4064)
			(stroke
				(width 0.1)
				(type default)
			)
			(layer "B.Fab")
		)
		(fp_line
			(start -1.1938 -0.406654)
			(end -1.1938 0.4064)
			(stroke
				(width 0.1)
				(type default)
			)
			(layer "B.Fab")
		)
		(pad "1" smd rect
			(at 0.7366 0 90)
			(size 0.7112 0.8128)
			(layers "B.Cu" "B.Mask" "B.Paste")
			(net "P3V3_AUX")
		)
		(pad "2" smd rect
			(at -0.7366 0 90)
			(size 0.7112 0.8128)
			(layers "B.Cu" "B.Mask" "B.Paste")
			(net "P3V3_AUX_FPGA_VCCIO4")
		)
	)
)
